# TIMECARD (Time Appliance Project (Time Card)) — schematic netlist excerpt (pin names and nets, part order shuffled) for the footprints in the layout excerpt that follows; sources: Cadence DE-HDL packaged netlist, KiCad conversion of R4006-B0001-02_R01.brd

L24  FERRITEBEAD  120OHM 25%  pkg SMC_0603R_H030  page 33 : \1\ = XP3R3V_FPGA ; \2\ = XP3R3V_FT4232
C43  CAPACITOR  18PF 50V 5%  pkg SMC_0201R  page 32 : \1\ = XP5R0V_COMP ; \2\ = XP5R0V_AGND

(kicad_pcb
	(version 20260206)
	(generator "pcbnew")
	(generator_version "10.0")
	(general
		(thickness 1.6)
		(legacy_teardrops no)
	)
	(paper "A4")
	(title_block
		(title "timecard-production-celestica-r4006 — R4006-B0001-02_R01.brd")
		(comment 1 "Time Appliance Project (Time Card) / footprints 161-162 of 1113")
	)
	(layers
		(0 "F.Cu" signal "TOP")
		(4 "In1.Cu" signal "L02_GND1")
		(6 "In2.Cu" signal "L03_SIG1")
		(8 "In3.Cu" signal "L04_GND2")
		(10 "In4.Cu" signal "L05_VCC1")
		(12 "In5.Cu" signal "L06_VCC2")
		(14 "In6.Cu" signal "L07_GND3")
		(16 "In7.Cu" signal "L08_SIG2")
		(18 "In8.Cu" signal "L09_GND4")
		(2 "B.Cu" signal "BOTTOM")
		(9 "F.Adhes" user "F.Adhesive")
		(11 "B.Adhes" user "B.Adhesive")
		(13 "F.Paste" user "Package Geometry/Pastemask Top")
		(15 "B.Paste" user "Package Geometry/Pastemask Bottom")
		(5 "F.SilkS" user "Ref Des/Silkscreen Top")
		(7 "B.SilkS" user "Ref Des/Silkscreen Bottom")
		(1 "F.Mask" user "Board Geometry/Soldermask Top")
		(3 "B.Mask" user "Board Geometry/Soldermask Bottom")
		(17 "Dwgs.User" user "User.Drawings")
		(19 "Cmts.User" user "User.Comments")
		(21 "Eco1.User" user "User.Eco1")
		(23 "Eco2.User" user "User.Eco2")
		(25 "Edge.Cuts" user "Board Geometry/Outline")
		(27 "Margin" user)
		(31 "F.CrtYd" user "Package Geometry/Place Bound Top")
		(29 "B.CrtYd" user "Package Geometry/Place Bound Bottom")
		(35 "F.Fab" user "Ref Des/Assembly Top")
		(33 "B.Fab" user "Ref Des/Assembly Bottom")
	)
	(footprint ""
		(layer "F.Cu")
		(at 36.957 -80.391 -90)
		(property "Reference" "L24"
			(at -1.5875 -0.03937 90)
			(unlocked yes)
			(layer "F.SilkS")
			(effects
				(font
					(size 0.7874 0.5842)
					(thickness 0.1524)
				)
				(justify left)
			)
		)
		(property "Value" "VAL*"
			(at -0.9398 3.70967 270)
			(unlocked yes)
			(layer "F.Fab")
			(hide yes)
			(effects
				(font
					(size 0.7874 0.5842)
					(thickness 0.1524)
				)
				(justify left)
			)
		)
		(property "Tolerance" "TOL*"
			(at -0.9906 5.00507 270)
			(unlocked yes)
			(layer "Cmts.User")
			(hide yes)
			(effects
				(font
					(size 0.7874 0.5842)
					(thickness 0.1524)
				)
				(justify left)
			)
		)
		(property "User Part Number" "PARTNUM*"
			(at -2.54 2.46507 270)
			(unlocked yes)
			(layer "Cmts.User")
			(hide yes)
			(effects
				(font
					(size 0.7874 0.5842)
					(thickness 0.1524)
				)
				(justify left)
			)
		)
		(property "Device Type" "FERRITEBEAD-G191-10100-01,120OA"
			(at -0.9906 1.22047 270)
			(unlocked yes)
			(layer "F.Fab")
			(hide yes)
			(effects
				(font
					(size 0.7874 0.5842)
					(thickness 0.1524)
				)
				(justify left)
			)
		)
		(duplicate_pad_numbers_are_jumpers no)
		(fp_line
			(start -1.3208 0.7112)
			(end -1.3208 -0.7112)
			(stroke
				(width 0.1)
				(type default)
			)
			(layer "F.SilkS")
		)
		(fp_line
			(start 1.3208 0.7112)
			(end -1.3208 0.7112)
			(stroke
				(width 0.1)
				(type default)
			)
			(layer "F.SilkS")
		)
		(fp_line
			(start -1.3208 -0.7112)
			(end 1.3208 -0.7112)
			(stroke
				(width 0.1)
				(type default)
			)
			(layer "F.SilkS")
		)
		(fp_line
			(start 1.3208 -0.7112)
			(end 1.3208 0.7112)
			(stroke
				(width 0.1)
				(type default)
			)
			(layer "F.SilkS")
		)
		(fp_rect
			(start -1.3208 0.7112)
			(end 1.3208 -0.7112)
			(stroke
				(width 0)
				(type default)
			)
			(fill no)
			(layer "F.CrtYd")
		)
		(fp_line
			(start -0.8128 0.4572)
			(end -0.8128 -0.4572)
			(stroke
				(width 0.1)
				(type default)
			)
			(layer "F.Fab")
		)
		(fp_line
			(start 0.8128 0.4572)
			(end -0.8128 0.4572)
			(stroke
				(width 0.1)
				(type default)
			)
			(layer "F.Fab")
		)
		(fp_line
			(start -0.8128 -0.4572)
			(end 0.8128 -0.4572)
			(stroke
				(width 0.1)
				(type default)
			)
			(layer "F.Fab")
		)
		(fp_line
			(start 0.8128 -0.4572)
			(end 0.8128 0.4572)
			(stroke
				(width 0.1)
				(type default)
			)
			(layer "F.Fab")
		)
		(pad "1" smd rect
			(at -0.6858 0 270)
			(size 0.762 0.8636)
			(layers "F.Cu" "F.Mask" "F.Paste")
			(net "XP3R3V_FPGA")
		)
		(pad "2" smd rect
			(at 0.6858 0 270)
			(size 0.762 0.8636)
			(layers "F.Cu" "F.Mask" "F.Paste")
			(net "XP3R3V_FT4232")
		)
		(zone
			(layer "F.Cu")
			(hatch none 0.5)
			(connect_pads
				(clearance 0)
			)
			(min_thickness 0.25)
			(keepout
				(tracks not_allowed)
				(vias allowed)
				(pads allowed)
				(copperpour not_allowed)
				(footprints allowed)
			)
			(placement
				(enabled no)
				(sheetname "")
			)
			(fill
				(thermal_gap 0.5)
				(thermal_bridge_width 0.5)
				(island_removal_mode 0)
			)
			(polygon
				(pts
					(xy 36.4998 -80.5434) (xy 36.4998 -80.2386) (xy 37.4142 -80.2386) (xy 37.4142 -80.5434)
				)
			)
		)
		(zone
			(layer "F.Cu")
			(hatch none 0.5)
			(connect_pads
				(clearance 0)
			)
			(min_thickness 0.25)
			(keepout
				(tracks allowed)
				(vias not_allowed)
				(pads allowed)
				(copperpour not_allowed)
				(footprints allowed)
			)
			(placement
				(enabled no)
				(sheetname "")
			)
			(fill
				(thermal_gap 0.5)
				(thermal_bridge_width 0.5)
				(island_removal_mode 0)
			)
			(polygon
				(pts
					(xy 36.4998 -80.5434) (xy 36.4998 -80.2386) (xy 37.4142 -80.2386) (xy 37.4142 -80.5434)
				)
			)
		)
	)
	(footprint ""
		(layer "F.Cu")
		(at 37.1094 -102.3874 180)
		(property "Reference" "C43"
			(at 4.2164 1.71323 0)
			(unlocked yes)
			(layer "F.SilkS")
			(effects
				(font
					(size 0.7874 0.5842)
					(thickness 0.1524)
				)
			)
		)
		(property "Value" "VAL*"
			(at 0.193548 2.13614 180)
			(unlocked yes)
			(layer "F.Fab")
			(hide yes)
			(effects
				(font
					(size 0.7874 0.5842)
					(thickness 0.1524)
				)
			)
		)
		(property "Tolerance" "TOL*"
			(at 0.216154 3.1496 180)
			(unlocked yes)
			(layer "Cmts.User")
			(hide yes)
			(effects
				(font
					(size 0.7874 0.5842)
					(thickness 0.1524)
				)
			)
		)
		(property "Device Type" "CAPACITOR-G104-0A180-FJ,18PF,5%"
			(at 0.184404 1.180592 180)
			(unlocked yes)
			(layer "F.Fab")
			(hide yes)
			(effects
				(font
					(size 0.7874 0.5842)
					(thickness 0.1524)
				)
			)
		)
		(property "User Part Number" "PARTNUM*"
			(at 0.216154 4.185666 180)
			(unlocked yes)
			(layer "Cmts.User")
			(hide yes)
			(effects
				(font
					(size 0.7874 0.5842)
					(thickness 0.1524)
				)
			)
		)
		(duplicate_pad_numbers_are_jumpers no)
		(fp_line
			(start 0.671322 0.4445)
			(end -0.671322 0.4445)
			(stroke
				(width 0.1)
				(type default)
			)
			(layer "F.SilkS")
		)
		(fp_line
			(start 0.671322 -0.4445)
			(end 0.671322 0.4445)
			(stroke
				(width 0.1)
				(type default)
			)
			(layer "F.SilkS")
		)
		(fp_line
			(start -0.671322 0.4445)
			(end -0.671322 -0.4445)
			(stroke
				(width 0.1)
				(type default)
			)
			(layer "F.SilkS")
		)
		(fp_line
			(start -0.671322 -0.4445)
			(end 0.671322 -0.4445)
			(stroke
				(width 0.1)
				(type default)
			)
			(layer "F.SilkS")
		)
		(fp_rect
			(start -0.671322 0.4445)
			(end 0.671322 -0.4445)
			(stroke
				(width 0)
				(type default)
			)
			(fill no)
			(layer "F.CrtYd")
		)
		(fp_line
			(start 0.31496 0.1651)
			(end 0.31496 -0.1651)
			(stroke
				(width 0.1)
				(type default)
			)
			(layer "F.Fab")
		)
		(fp_line
			(start 0.31496 -0.1651)
			(end -0.31496 -0.1651)
			(stroke
				(width 0.1)
				(type default)
			)
			(layer "F.Fab")
		)
		(fp_line
			(start -0.31496 0.1651)
			(end 0.31496 0.1651)
			(stroke
				(width 0.1)
				(type default)
			)
			(layer "F.Fab")
		)
		(fp_line
			(start -0.31496 -0.1651)
			(end -0.31496 0.1651)
			(stroke
				(width 0.1)
				(type default)
			)
			(layer "F.Fab")
		)
		(pad "1" smd rect
			(at -0.264922 0 180)
			(size 0.3048 0.381)
			(layers "F.Cu" "F.Mask" "F.Paste")
			(net "XP5R0V_COMP")
		)
		(pad "2" smd rect
			(at 0.264922 0 180)
			(size 0.3048 0.381)
			(layers "F.Cu" "F.Mask" "F.Paste")
			(net "XP5R0V_AGND")
		)
		(zone
			(layer "F.Cu")
			(hatch none 0.5)
			(connect_pads
				(clearance 0)
			)
			(min_thickness 0.25)
			(keepout
				(tracks allowed)
				(vias not_allowed)
				(pads allowed)
				(copperpour not_allowed)
				(footprints allowed)
			)
			(placement
				(enabled no)
				(sheetname "")
			)
			(fill
				(thermal_gap 0.5)
				(thermal_bridge_width 0.5)
				(island_removal_mode 0)
			)
			(polygon
				(pts
					(xy 37.221922 -102.5779) (xy 36.996878 -102.5779) (xy 36.996878 -102.1969) (xy 37.221922 -102.1969)
				)
			)
		)
	)
)
